# T6G (Grand Teton) — schematic netlist excerpt (pin names and nets, part order shuffled) for the footprints in the layout excerpt that follows; sources: Cadence DE-HDL packaged netlist, KiCad conversion of 04192023_DAF0TMB3IC0_F0TG_MB_C_brd_V02_OCP.brd

PC6024  Q_CAP  22UF 4V 20% X6S  pkg C0805  page 270 : A = P1V2_AUX ; B = GND

X8006  TP_TDR_4P_FTS  TP_TDR_4P_DIP EMPTY  pkg TH  page 260
  S1  = TDR_DIFF_85_BOT_DP
  P1  = T1_GND
  P2  = T1_GND
  S2  = TDR_DIFF_85_BOT_DN

(kicad_pcb
	(version 20260206)
	(generator "pcbnew")
	(generator_version "10.0")
	(general
		(thickness 1.6)
		(legacy_teardrops no)
	)
	(paper "A4")
	(title_block
		(title "04192023_DAF0TMB3IC0_F0TG_MB_C_brd_V02_OCP.brd")
		(comment 1 "Grand Teton / footprints 7403-7404 of 8354")
	)
	(layers
		(0 "F.Cu" signal "TOP")
		(4 "In1.Cu" signal "GND")
		(6 "In2.Cu" signal "IN1")
		(8 "In3.Cu" signal "GND1")
		(10 "In4.Cu" signal "IN2")
		(12 "In5.Cu" signal "GND2")
		(14 "In6.Cu" signal "IN3")
		(16 "In7.Cu" signal "GND3")
		(18 "In8.Cu" signal "VCC")
		(20 "In9.Cu" signal "VCC1")
		(22 "In10.Cu" signal "GND4")
		(24 "In11.Cu" signal "IN4")
		(26 "In12.Cu" signal "GND5")
		(28 "In13.Cu" signal "IN5")
		(30 "In14.Cu" signal "GND6")
		(32 "In15.Cu" signal "IN6")
		(34 "In16.Cu" signal "GND7")
		(2 "B.Cu" signal "BOTTOM")
		(9 "F.Adhes" user "F.Adhesive")
		(11 "B.Adhes" user "B.Adhesive")
		(13 "F.Paste" user "Package Geometry/Pastemask Top")
		(15 "B.Paste" user "Package Geometry/Pastemask Bottom")
		(5 "F.SilkS" user "Ref Des/Silkscreen Top")
		(7 "B.SilkS" user "Ref Des/Silkscreen Bottom")
		(1 "F.Mask" user "Board Geometry/Soldermask Top")
		(3 "B.Mask" user "Board Geometry/Soldermask Bottom")
		(17 "Dwgs.User" user "User.Drawings")
		(19 "Cmts.User" user "User.Comments")
		(21 "Eco1.User" user "User.Eco1")
		(23 "Eco2.User" user "User.Eco2")
		(25 "Edge.Cuts" user "Board Geometry/Outline")
		(27 "Margin" user)
		(31 "F.CrtYd" user "Package Geometry/Place Bound Top")
		(29 "B.CrtYd" user "Package Geometry/Place Bound Bottom")
		(35 "F.Fab" user "Ref Des/Assembly Top")
		(33 "B.Fab" user "Ref Des/Assembly Bottom")
	)
	(footprint ""
		(layer "B.Cu")
		(at 482.66985 7.613142 90)
		(property "Reference" "X8006"
			(at 0.93726 -1.53035 270)
			(unlocked yes)
			(layer "B.SilkS")
			(effects
				(font
					(size 0.7874 0.5842)
					(thickness 0.1524)
				)
				(justify left mirror)
			)
		)
		(property "Value" ""
			(at 0 0 90)
			(layer "B.Fab")
			(effects
				(font
					(size 1.27 1.27)
				)
				(justify mirror)
			)
		)
		(property "Device Type" "TP_TDR_4P_FTS_TH-TP_TDR_4P_DIP,EMPTY,TP15"
			(at -1.30175 1.27 0)
			(unlocked yes)
			(layer "B.Fab")
			(hide yes)
			(effects
				(font
					(size 0.635 0.4064)
					(thickness 0.1524)
				)
				(justify mirror)
			)
		)
		(property "User Part Number" "N_A"
			(at -1.30175 1.27 0)
			(unlocked yes)
			(layer "Cmts.User")
			(hide yes)
			(effects
				(font
					(size 0.635 0.4064)
					(thickness 0.1524)
				)
				(justify mirror)
			)
		)
		(duplicate_pad_numbers_are_jumpers no)
		(fp_line
			(start 0 -1.27)
			(end 0 -0.635)
			(stroke
				(width 0.1524)
				(type default)
			)
			(layer "B.SilkS")
		)
		(fp_line
			(start -2.54 -1.27)
			(end 0 -1.27)
			(stroke
				(width 0.1524)
				(type default)
			)
			(layer "B.SilkS")
		)
		(fp_line
			(start -2.54 -1.1303)
			(end -2.54 -1.27)
			(stroke
				(width 0.1524)
				(type default)
			)
			(layer "B.SilkS")
		)
		(fp_line
			(start 0 0.635)
			(end 0 1.905)
			(stroke
				(width 0.1524)
				(type default)
			)
			(layer "B.SilkS")
		)
		(fp_line
			(start -2.54 1.4097)
			(end -2.54 1.1303)
			(stroke
				(width 0.1524)
				(type default)
			)
			(layer "B.SilkS")
		)
		(fp_line
			(start 0 3.175)
			(end 0 3.81)
			(stroke
				(width 0.1524)
				(type default)
			)
			(layer "B.SilkS")
		)
		(fp_line
			(start 0 3.81)
			(end -2.54 3.81)
			(stroke
				(width 0.1524)
				(type default)
			)
			(layer "B.SilkS")
		)
		(fp_line
			(start -2.54 3.81)
			(end -2.54 3.6703)
			(stroke
				(width 0.1524)
				(type default)
			)
			(layer "B.SilkS")
		)
		(fp_poly
			(pts
				(xy 0.761746 0) (xy 2.285746 -0.762) (xy 2.285746 0.762)
			)
			(stroke
				(width 0)
				(type default)
			)
			(fill yes)
			(layer "B.SilkS")
		)
		(fp_line
			(start 0 -1.27)
			(end 0 3.81)
			(stroke
				(width 0.1)
				(type default)
			)
			(layer "B.Fab")
		)
		(fp_line
			(start -2.54 -1.27)
			(end 0 -1.27)
			(stroke
				(width 0.1)
				(type default)
			)
			(layer "B.Fab")
		)
		(fp_line
			(start 0 3.81)
			(end -2.54 3.81)
			(stroke
				(width 0.1)
				(type default)
			)
			(layer "B.Fab")
		)
		(fp_line
			(start -2.54 3.81)
			(end -2.54 -1.27)
			(stroke
				(width 0.1)
				(type default)
			)
			(layer "B.Fab")
		)
		(fp_poly
			(pts
				(xy 0.761746 0) (xy 2.285746 -0.762) (xy 2.285746 0.762)
			)
			(stroke
				(width 0)
				(type default)
			)
			(fill yes)
			(layer "B.Fab")
		)
		(pad "1" thru_hole circle
			(at 0 0 270)
			(size 1.0033 1.0033)
			(drill 0.249936)
			(layers "*.Cu" "*.Mask")
			(remove_unused_layers no)
			(net "TDR_DIFF_85_BOT_DP")
			(clearance 0.10795)
			(padstack
				(mode front_inner_back)
				(layer "Inner"
					(shape circle)
					(size 0.8001 0.8001)
					(clearance 0.1524)
				)
				(layer "B.Cu"
					(shape circle)
					(size 1.0033 1.0033)
					(thermal_gap 0.10795)
					(clearance 0.10795)
				)
			)
		)
		(pad "2" thru_hole circle
			(at -2.54 0 270)
			(size 1.9939 1.9939)
			(drill 0.249936)
			(layers "*.Cu" "*.Mask")
			(remove_unused_layers no)
			(net "T1_GND")
			(clearance 0.10795)
			(padstack
				(mode front_inner_back)
				(layer "Inner"
					(shape circle)
					(size 0.8001 0.8001)
					(clearance 0.1524)
				)
				(layer "B.Cu"
					(shape circle)
					(size 1.9939 1.9939)
					(thermal_gap 0.10795)
					(clearance 0.10795)
				)
			)
		)
		(pad "3" thru_hole circle
			(at -2.54 2.54 270)
			(size 1.9939 1.9939)
			(drill 0.249936)
			(layers "*.Cu" "*.Mask")
			(remove_unused_layers no)
			(net "T1_GND")
			(clearance 0.10795)
			(padstack
				(mode front_inner_back)
				(layer "Inner"
					(shape circle)
					(size 0.8001 0.8001)
					(clearance 0.1524)
				)
				(layer "B.Cu"
					(shape circle)
					(size 1.9939 1.9939)
					(thermal_gap 0.10795)
					(clearance 0.10795)
				)
			)
		)
		(pad "4" thru_hole circle
			(at 0 2.54 270)
			(size 1.0033 1.0033)
			(drill 0.249936)
			(layers "*.Cu" "*.Mask")
			(remove_unused_layers no)
			(net "TDR_DIFF_85_BOT_DN")
			(clearance 0.10795)
			(padstack
				(mode front_inner_back)
				(layer "Inner"
					(shape circle)
					(size 0.8001 0.8001)
					(clearance 0.1524)
				)
				(layer "B.Cu"
					(shape circle)
					(size 1.0033 1.0033)
					(thermal_gap 0.10795)
					(clearance 0.10795)
				)
			)
		)
	)
	(footprint ""
		(layer "B.Cu")
		(at 130.104642 -76.48321)
		(property "Reference" "PC6024"
			(at 0 0 0)
			(layer "B.SilkS")
			(hide yes)
			(effects
				(font
					(size 1.27 1.27)
				)
				(justify mirror)
			)
		)
		(property "Value" ""
			(at 0 0 0)
			(layer "B.Fab")
			(effects
				(font
					(size 1.27 1.27)
				)
				(justify mirror)
			)
		)
		(duplicate_pad_numbers_are_jumpers no)
		(fp_line
			(start -1.524 -0.762)
			(end -1.524 0.762)
			(stroke
				(width 0.1524)
				(type default)
			)
			(layer "B.SilkS")
		)
		(fp_line
			(start -1.524 0.762)
			(end 1.524 0.762)
			(stroke
				(width 0.1524)
				(type default)
			)
			(layer "B.SilkS")
		)
		(fp_line
			(start 1.524 -0.762)
			(end -1.524 -0.762)
			(stroke
				(width 0.1524)
				(type default)
			)
			(layer "B.SilkS")
		)
		(fp_line
			(start 1.524 0.762)
			(end 1.524 -0.762)
			(stroke
				(width 0.1524)
				(type default)
			)
			(layer "B.SilkS")
		)
		(fp_line
			(start -1.1049 -0.724916)
			(end 1.1049 -0.724916)
			(stroke
				(width 0.1)
				(type default)
			)
			(layer "B.Fab")
		)
		(fp_line
			(start -1.1049 0.724916)
			(end -1.1049 -0.724916)
			(stroke
				(width 0.1)
				(type default)
			)
			(layer "B.Fab")
		)
		(fp_line
			(start 1.1049 -0.724916)
			(end 1.1049 0.724916)
			(stroke
				(width 0.1)
				(type default)
			)
			(layer "B.Fab")
		)
		(fp_line
			(start 1.1049 0.724916)
			(end -1.1049 0.724916)
			(stroke
				(width 0.1)
				(type default)
			)
			(layer "B.Fab")
		)
		(pad "1" smd rect
			(at 0.889 0)
			(size 1.016 1.27)
			(layers "B.Cu" "B.Mask" "B.Paste")
			(net "P1V2_AUX")
		)
		(pad "2" smd rect
			(at -0.889 0)
			(size 1.016 1.27)
			(layers "B.Cu" "B.Mask" "B.Paste")
			(net "GND")
		)
	)
)
